G04 ================== begin FILE IDENTIFICATION RECORD ==================*
G04 Layout Name:  15105-sa.brd*
G04 Film Name:    P_OUTLINE*
G04 File Format:  Gerber RS274X*
G04 File Origin:  Cadence Allegro 16.5-S056*
G04 Origin Date:  Wed Nov 16 02:01:36 2016*
G04 *
G04 Layer:  BOARD GEOMETRY/PANEL_OUTLINE*
G04 *
G04 Offset:    (0.00 0.00)*
G04 Mirror:    No*
G04 Mode:      Positive*
G04 Rotation:  0*
G04 FullContactRelief:  No*
G04 UndefLineWidth:     6.00*
G04 ================== end FILE IDENTIFICATION RECORD ====================*
%FSLAX35Y35*MOIN*%
%IR0*IPPOS*OFA0.00000B0.00000*MIA0B0*SFA1.00000B1.00000*%
%ADD10C,.006*%
G75*
%LPD*%
G75*
G54D10*
G01X1425733Y-51181D02*
X-29385D01*
G01X-33322Y-47244D02*
G03X-29385Y-51181I3937J0D01*
G01X-33322Y-47244D02*
Y893701D01*
G01X-7874Y102402D02*
Y212205D01*
G01Y102402D02*
G03X0Y94528I7874J0D01*
G01Y212205D02*
G03X-7874I-3937J0D01*
G01Y237402D02*
G03X0I3937J-1D01*
G01X-7874D02*
Y406693D01*
G01X0D02*
G03X-7874I-3937J0D01*
G01Y431890D02*
G03X0I3937J0D01*
G01X-7874D02*
Y601181D01*
G01X0D02*
G03X-7874I-3937J0D01*
G01Y626378D02*
Y795669D01*
G01Y626378D02*
G03X0I3937J0D01*
G01Y795669D02*
G03X-7874I-3937J0D01*
G01Y820866D02*
G03X0I3937J0D01*
G01X-7874Y844488D02*
Y820866D01*
G01X-3937Y848425D02*
G03X-7874Y844488I0J-3937D01*
G01X93307Y848425D02*
X-3937D01*
G01X-29385Y897638D02*
G03X-33322Y893701I0J-3937D01*
G01X-29385Y897638D02*
X93307D01*
G01X98425Y94528D02*
X0D01*
G01X1400000Y36220D02*
G03X1398031Y38189I-1969J0D01*
G01X1396654D01*
G02X1394685Y40157I0J1969D01*
G01Y71654D01*
G02X1396654Y73622I1969J-1D01*
G01X1398031D01*
G03X1400000Y75591I0J1969D01*
G01Y836614D01*
G03X1396063Y840551I-3937J0D01*
G01X1368504D01*
G02X1363386Y845669I0J5118D01*
G01Y871654D01*
G03X1361417Y873622I-1969J-1D01*
G01X1358268D01*
G02X1356299Y875591I0J1969D01*
G01Y892521D01*
X1352363Y897638D01*
X1218110D01*
X1214173Y892520D01*
Y875984D01*
G02X1205512I-4331J0D01*
G01Y892520D01*
X1201575Y897638D01*
X1029528D01*
X1025591Y892520D01*
Y875591D01*
G02X1023622Y873622I-1969J0D01*
G01X1020472D01*
G03X1018504Y871654I0J-1968D01*
G01Y845669D01*
G02X1013386Y840551I-5118J0D01*
G01X1008433D01*
G03X988748Y820866I0J-19685D01*
G01Y650669D01*
G02X983748Y645669I-5000J0D01*
G01X926819D01*
G02X921819Y650669I0J5000D01*
G01Y820866D01*
G03X902134Y840551I-19685J0D01*
G01X872441D01*
G02X867323Y845669I0J5118D01*
G01Y871654D01*
G03X865354Y873622I-1969J-1D01*
G01X862205D01*
G02X860236Y875591I0J1969D01*
G01Y892521D01*
X856300Y897638D01*
X722048D01*
X718110Y892519D01*
Y875984D01*
G02X709449I-4331J0D01*
G01Y892520D01*
X705512Y897638D01*
X533465D01*
X529528Y892520D01*
Y875591D01*
G02X527559Y873622I-1969J0D01*
G01X524409D01*
G03X522441Y871654I0J-1968D01*
G01Y845669D01*
G02X517323Y840551I-5118J0D01*
G01X455118D01*
G02X450000Y845669I0J5118D01*
G01Y871654D01*
G03X448031Y873622I-1968J0D01*
G01X444882D01*
G02X442913Y875591I0J1969D01*
G01Y892521D01*
X438977Y897638D01*
X304725D01*
X300787Y892519D01*
Y875984D01*
G02X292126I-4331J0D01*
G01Y892521D01*
X288190Y897638D01*
X116142D01*
X112205Y892520D01*
Y875591D01*
G02X110236Y873622I-1969J0D01*
G01X107087D01*
G03X105118Y871654I0J-1969D01*
G01Y845669D01*
G02X100000Y840551I-5118J0D01*
G01X3937D01*
G03X0Y836614I0J-3937D01*
G01Y110276D01*
G03X7874Y102402I7874J0D01*
G01X196654D01*
G02X204528Y94528I0J-7874D01*
G01Y7874D01*
G03X212402Y0I7874J0D01*
G01X471014D01*
G02X478888Y-7874I0J-7874D01*
G01Y-11811D01*
G03X486762Y-19685I7874J0D01*
G01X1302165D01*
G03X1306102Y-15748I0J3937D01*
G01Y-3937D01*
G02X1310039Y0I3937J0D01*
G01X1396063D01*
G03X1400000Y3937I0J3937D01*
G01Y36220D01*
G01X93307Y848425D02*
G03X97244Y852362I0J3937D01*
G01Y893701D02*
Y852362D01*
G01Y893701D02*
G03X93307Y897638I-3937J0D01*
G01X192717Y94528D02*
X123622D01*
G01Y102402D02*
G03Y94528I0J-3937D01*
G01X98425D02*
G03Y102402I0J3937D01*
G01X196654Y0D02*
G03X204528Y-7874I7874J0D01*
G01X196654Y0D02*
Y29961D01*
G01X204528D02*
G03X196654I-3937J0D01*
G01Y55157D02*
Y90591D01*
G01Y55157D02*
G03X204528I3937J0D01*
G01X196654Y90591D02*
G03X192717Y94528I-3937J0D01*
G01X232077Y-7874D02*
G03Y0I0J3937D01*
G01Y-7874D02*
X204528D01*
G01X434439D02*
X257274D01*
G01Y0D02*
G03Y-7874I0J-3937D01*
G01X365945Y38188D02*
G03X367914Y40156I0J1969D01*
G01X354134D02*
G03X356103Y38188I1969J1D01*
G01D02*
X365945D01*
G01X354134Y71653D02*
Y40156D01*
G01X367914Y71653D02*
G03X365945Y73621I-1969J-1D01*
G01X356103D02*
G03X354134Y71653I0J-1969D01*
G01X365945Y73621D02*
X356103D01*
G01X367914Y40156D02*
Y71653D01*
G01X434439Y-7874D02*
G03Y0I0J3937D01*
G01X471014Y-15748D02*
G03X463140Y-7874I-7874J0D01*
G01D02*
X459636D01*
G01Y0D02*
G03Y-7874I0J-3937D01*
G01X707234Y-27559D02*
X478888D01*
G01X471014Y-19685D02*
G03X478888Y-27559I7874J0D01*
G01X471014Y-19685D02*
Y-15748D01*
G01X870226Y-27559D02*
X732431D01*
G01Y-19685D02*
G03Y-27559I0J-3937D01*
G01X707234D02*
G03Y-19685I0J3937D01*
G01X870226Y-27559D02*
G03Y-19685I1J3937D01*
G01X1072589Y-27559D02*
X895423D01*
G01Y-19685D02*
G03Y-27559I0J-3937D01*
G01X1072589D02*
G03Y-19685I0J3937D01*
G01X1097785D02*
G03Y-27559I1J-3937D01*
G01X1336086Y-8662D02*
X1318701D01*
G03X1314764Y-12599I0J-3937D01*
G01Y-23622D01*
G02X1310827Y-27559I-3937J0D01*
G01X1097785D01*
G01X1336086Y-8662D02*
G03Y-1I0J4330D01*
G01X1361283D02*
G03Y-8662I0J-4330D01*
G01X1407874Y13026D02*
Y-4725D01*
G02X1403937Y-8662I-3937J0D01*
G01X1361283D01*
G01X1403937Y848425D02*
X1375197D01*
G01X1371260Y852362D02*
G03X1375197Y848425I3937J0D01*
G01X1371260Y852362D02*
Y893701D01*
G01X1375197Y897638D02*
G03X1371260Y893701I0J-3937D01*
G01X1375197Y897638D02*
X1425733D01*
G01X1407874Y30709D02*
Y219685D01*
G01X1400000Y30709D02*
G03X1407874I3937J0D01*
G01Y13026D02*
G03X1400000I-3937J-1D01*
G01X1407874Y219685D02*
G03X1400000I-3937J0D01*
G01Y244882D02*
G03X1407874I3937J0D01*
G01Y414173D02*
Y244882D01*
G01Y608661D02*
Y439370D01*
G01X1400000D02*
G03X1407874I3937J0D01*
G01Y414173D02*
G03X1400000I-3937J0D01*
G01X1407874Y608661D02*
G03X1400000I-3937J0D01*
G01Y626378D02*
G03X1407874I3937J0D01*
G01Y795669D02*
Y626378D01*
G01Y795669D02*
G03X1400000I-3937J0D01*
G01Y820866D02*
G03X1407874I3937J0D01*
G01Y844488D02*
Y820866D01*
G01Y844488D02*
G03X1403937Y848425I-3937J0D01*
G01X1429670Y893701D02*
Y-47244D01*
G01X1425733Y-51181D02*
G03X1429670Y-47244I0J3937D01*
G01Y893701D02*
G03X1425733Y897638I-3937J0D01*
M02*
